(kicad_pcb
	(version 20240108)
	(generator "pcbnew")
	(generator_version "8.0")
	(general
		(thickness 1.62)
		(legacy_teardrops no)
	)
	(paper "A4")
	(title_block
		(title "Jetson Orin Baseboard")
		(date "2025-03-12")
		(rev "1.3.4")
		(company "Antmicro Ltd")
		(comment 1 "www.antmicro.com")
		(comment 9 "footprints 201-204 of 677")
	)
	(layers
		(0 "F.Cu" signal)
		(1 "In1.Cu" signal)
		(2 "In2.Cu" signal)
		(3 "In3.Cu" signal)
		(4 "In4.Cu" jumper)
		(5 "In5.Cu" signal)
		(6 "In6.Cu" signal)
		(31 "B.Cu" signal)
		(32 "B.Adhes" user "B.Adhesive")
		(33 "F.Adhes" user "F.Adhesive")
		(34 "B.Paste" user)
		(35 "F.Paste" user)
		(36 "B.SilkS" user "B.Silkscreen")
		(37 "F.SilkS" user "F.Silkscreen")
		(38 "B.Mask" user)
		(39 "F.Mask" user)
		(40 "Dwgs.User" user "User.Drawings")
		(41 "Cmts.User" user "User.Comments")
		(42 "Eco1.User" user "User.Eco1")
		(43 "Eco2.User" user "User.Eco2")
		(44 "Edge.Cuts" user)
		(45 "Margin" user)
		(46 "B.CrtYd" user "B.Courtyard")
		(47 "F.CrtYd" user "F.Courtyard")
		(48 "B.Fab" user)
		(49 "F.Fab" user)
	)
	(footprint "antmicro-footprints:R_0402_1005Metric"
		(layer "F.Cu")
		(at 68.27 85.5 180)
		(descr "Resistor SMD 0402")
		(tags "resistor SMD 0402")
		(property "Reference" "R5"
			(at -4.14 3.15 0)
			(layer "F.SilkS")
			(effects
				(font
					(size 0.7 0.7)
					(thickness 0.15)
				)
				(justify right bottom)
			)
		)
		(property "Value" "R_0R_0402"
			(at 0 1.4 0)
			(layer "F.Fab")
			(effects
				(font
					(size 0.7 0.7)
					(thickness 0.15)
				)
				(justify right bottom)
			)
		)
		(property "Footprint" "antmicro-footprints:R_0402_1005Metric"
			(at 0 0 0)
			(layer "F.Fab")
			(hide yes)
			(effects
				(font
					(size 1.27 1.27)
					(thickness 0.15)
				)
			)
		)
		(property "Datasheet" "https://industrial.panasonic.com/cdbs/www-data/pdf/RDA0000/AOA0000C301.pdf"
			(at 0 0 0)
			(layer "F.Fab")
			(hide yes)
			(effects
				(font
					(size 1.27 1.27)
					(thickness 0.15)
				)
			)
		)
		(property "Author" "Antmicro"
			(at -16.4 149.4 90)
			(layer "F.Fab")
			(hide yes)
			(effects
				(font
					(size 1 1)
					(thickness 0.15)
				)
			)
		)
		(property "Current" "1A"
			(at -16.4 149.4 90)
			(layer "F.Fab")
			(hide yes)
			(effects
				(font
					(size 1 1)
					(thickness 0.15)
				)
			)
		)
		(property "License" "Apache-2.0"
			(at -16.4 149.4 90)
			(layer "F.Fab")
			(hide yes)
			(effects
				(font
					(size 1 1)
					(thickness 0.15)
				)
			)
		)
		(property "MPN" "ERJ2GE0R00X"
			(at -16.4 149.4 90)
			(layer "F.Fab")
			(hide yes)
			(effects
				(font
					(size 1 1)
					(thickness 0.15)
				)
			)
		)
		(property "Manufacturer" "Panasonic"
			(at -16.4 149.4 90)
			(layer "F.Fab")
			(hide yes)
			(effects
				(font
					(size 1 1)
					(thickness 0.15)
				)
			)
		)
		(property "Tolerance" ""
			(at -16.4 149.4 90)
			(layer "F.Fab")
			(hide yes)
			(effects
				(font
					(size 1 1)
					(thickness 0.15)
				)
			)
		)
		(property "Val" "0R"
			(at -16.4 149.4 90)
			(layer "F.Fab")
			(hide yes)
			(effects
				(font
					(size 1 1)
					(thickness 0.15)
				)
			)
		)
		(sheetname "SoM")
		(sheetfile "som.kicad_sch")
		(attr smd exclude_from_pos_files exclude_from_bom dnp)
		(fp_rect
			(start -0.925 -0.47)
			(end 0.925 0.47)
			(stroke
				(width 0.05)
				(type default)
			)
			(fill none)
			(layer "F.CrtYd")
		)
		(fp_rect
			(start -0.5 -0.25)
			(end 0.5 0.25)
			(stroke
				(width 0.15)
				(type solid)
			)
			(fill none)
			(layer "F.Fab")
		)
		(fp_text user "License: Apache-2.0"
			(at -0.95 5.169 0)
			(layer "F.Fab")
			(hide yes)
			(effects
				(font
					(size 0.7 0.7)
					(thickness 0.15)
				)
				(justify right bottom)
			)
		)
		(fp_text user "Author: Antmicro"
			(at -0.95 4.169 0)
			(layer "F.Fab")
			(hide yes)
			(effects
				(font
					(size 0.7 0.7)
					(thickness 0.15)
				)
				(justify right bottom)
			)
		)
		(fp_text user "${REFERENCE}"
			(at -0.95 3.168 0)
			(layer "F.Fab")
			(hide yes)
			(effects
				(font
					(size 0.7 0.7)
					(thickness 0.15)
				)
				(justify right bottom)
			)
		)
		(pad "1" smd roundrect
			(at -0.48 0 180)
			(size 0.59 0.64)
			(layers "F.Cu" "F.Paste" "F.Mask")
			(roundrect_rratio 0.25)
			(net 753 "Net-(J15H-GPIO13{slash}PWM)")
			(pintype "passive")
		)
		(pad "2" smd roundrect
			(at 0.48 0 180)
			(size 0.59 0.64)
			(layers "F.Cu" "F.Paste" "F.Mask")
			(roundrect_rratio 0.25)
			(net 243 "VSYNC_CAM3")
			(pintype "passive")
		)
	)
	(footprint "antmicro-footprints:XDFN-2_1x0.60mm"
		(layer "F.Cu")
		(at 147.45 89.5 90)
		(property "Reference" "D49"
			(at 7 -0.15 0)
			(layer "F.SilkS")
			(effects
				(font
					(size 0.7 0.7)
					(thickness 0.15)
				)
				(justify left bottom)
			)
		)
		(property "Value" "TPD1E0B04_XDFN-2"
			(at 0 1.5 90)
			(layer "F.Fab")
			(effects
				(font
					(size 0.7 0.7)
					(thickness 0.15)
				)
				(justify left bottom)
			)
		)
		(property "Footprint" "antmicro-footprints:XDFN-2_1x0.60mm"
			(at 0 0 90)
			(layer "F.Fab")
			(hide yes)
			(effects
				(font
					(size 1.27 1.27)
					(thickness 0.15)
				)
			)
		)
		(property "Datasheet" "https://www.ti.com/general/docs/suppproductinfo.tsp?distId=26&gotoUrl=https://www.ti.com/lit/gpn/tpd1e0b04"
			(at 0 0 90)
			(layer "F.Fab")
			(hide yes)
			(effects
				(font
					(size 1.27 1.27)
					(thickness 0.15)
				)
			)
		)
		(property "MPN" "TPD1E0B04DPYR"
			(at 236.95 -57.95 0)
			(layer "F.Fab")
			(hide yes)
			(effects
				(font
					(size 1 1)
					(thickness 0.15)
				)
			)
		)
		(property "Manufacturer" "Texas Instruments"
			(at 236.95 -57.95 0)
			(layer "F.Fab")
			(hide yes)
			(effects
				(font
					(size 1 1)
					(thickness 0.15)
				)
			)
		)
		(property "Author" "Antmicro"
			(at 236.95 -57.95 0)
			(layer "F.Fab")
			(hide yes)
			(effects
				(font
					(size 1 1)
					(thickness 0.15)
				)
			)
		)
		(property "License" "Apache-2.0"
			(at 236.95 -57.95 0)
			(layer "F.Fab")
			(hide yes)
			(effects
				(font
					(size 1 1)
					(thickness 0.15)
				)
			)
		)
		(sheetname "Peripherals")
		(sheetfile "peripherals.kicad_sch")
		(attr smd)
		(fp_rect
			(start -0.725 -0.475)
			(end 0.725 0.475)
			(stroke
				(width 0.05)
				(type solid)
			)
			(fill none)
			(layer "F.CrtYd")
		)
		(fp_rect
			(start -0.55 -0.35)
			(end 0.55 0.35)
			(stroke
				(width 0.15)
				(type solid)
			)
			(fill none)
			(layer "F.Fab")
		)
		(fp_text user "License: Apache-2.0"
			(at -0.8 5.6 90)
			(layer "F.Fab")
			(hide yes)
			(effects
				(font
					(size 0.7 0.7)
					(thickness 0.15)
				)
				(justify left bottom)
			)
		)
		(fp_text user "Author: Antmicro"
			(at -0.8 4.4 90)
			(layer "F.Fab")
			(hide yes)
			(effects
				(font
					(size 0.7 0.7)
					(thickness 0.15)
				)
				(justify left bottom)
			)
		)
		(fp_text user "${REFERENCE}"
			(at -0.8 3.2 90)
			(layer "F.Fab")
			(hide yes)
			(effects
				(font
					(size 0.7 0.7)
					(thickness 0.15)
				)
				(justify left bottom)
			)
		)
		(pad "1" smd roundrect
			(at -0.351 0 90)
			(size 0.3 0.5)
			(layers "F.Cu" "F.Paste" "F.Mask")
			(roundrect_rratio 0.25)
			(net 471 "PCIE3_CLK_N")
			(pinfunction "C")
			(pintype "passive")
		)
		(pad "2" smd roundrect
			(at 0.349 0 90)
			(size 0.3 0.5)
			(layers "F.Cu" "F.Paste" "F.Mask")
			(roundrect_rratio 0.25)
			(net 1 "GND")
			(pinfunction "A")
			(pintype "passive")
		)
	)
	(footprint "antmicro-footprints:R_0603_1608Metric"
		(layer "F.Cu")
		(at 68.525 91.675 90)
		(descr "Resistor SMD 0603")
		(tags "resistor SMD 0603")
		(property "Reference" "R178"
			(at -4.005 0.46 90)
			(layer "F.SilkS")
			(effects
				(font
					(size 0.7 0.7)
					(thickness 0.15)
				)
				(justify left bottom)
			)
		)
		(property "Value" "R_0R_22.4A_0603"
			(at 0 1.6 90)
			(layer "F.Fab")
			(effects
				(font
					(size 0.7 0.7)
					(thickness 0.15)
				)
				(justify left bottom)
			)
		)
		(property "Footprint" "antmicro-footprints:R_0603_1608Metric"
			(at 0 0 90)
			(layer "F.Fab")
			(hide yes)
			(effects
				(font
					(size 1.27 1.27)
					(thickness 0.15)
				)
			)
		)
		(property "Datasheet" "https://fscdn.rohm.com/en/products/databook/datasheet/passive/resistor/chip_resistor/pmr-jpw-e.pdf"
			(at 0 0 90)
			(layer "F.Fab")
			(hide yes)
			(effects
				(font
					(size 1.27 1.27)
					(thickness 0.15)
				)
			)
		)
		(property "Author" "Antmicro"
			(at 160.11 23.23 0)
			(layer "F.Fab")
			(hide yes)
			(effects
				(font
					(size 1 1)
					(thickness 0.15)
				)
			)
		)
		(property "License" "Apache-2.0"
			(at 160.11 23.23 0)
			(layer "F.Fab")
			(hide yes)
			(effects
				(font
					(size 1 1)
					(thickness 0.15)
				)
			)
		)
		(property "MPN" "PMR03EZPJ000"
			(at 160.11 23.23 0)
			(layer "F.Fab")
			(hide yes)
			(effects
				(font
					(size 1 1)
					(thickness 0.15)
				)
			)
		)
		(property "Manufacturer" "ROHM Semiconductor"
			(at 160.11 23.23 0)
			(layer "F.Fab")
			(hide yes)
			(effects
				(font
					(size 1 1)
					(thickness 0.15)
				)
			)
		)
		(property "Max. Curr." "22.4A"
			(at 160.11 23.23 0)
			(layer "F.Fab")
			(hide yes)
			(effects
				(font
					(size 1 1)
					(thickness 0.15)
				)
			)
		)
		(property "Tolerance" "template_tolerance"
			(at 160.11 23.23 0)
			(layer "F.Fab")
			(hide yes)
			(effects
				(font
					(size 1 1)
					(thickness 0.15)
				)
			)
		)
		(property "Val" "0R"
			(at 160.11 23.23 0)
			(layer "F.Fab")
			(hide yes)
			(effects
				(font
					(size 1 1)
					(thickness 0.15)
				)
			)
		)
		(sheetname "Supply")
		(sheetfile "supply.kicad_sch")
		(attr smd)
		(fp_line
			(start -0.15 -0.4)
			(end 0.15 -0.4)
			(stroke
				(width 0.15)
				(type solid)
			)
			(layer "F.SilkS")
		)
		(fp_line
			(start -0.15 0.4)
			(end 0.15 0.4)
			(stroke
				(width 0.15)
				(type solid)
			)
			(layer "F.SilkS")
		)
		(fp_rect
			(start -1.25 -0.65)
			(end 1.25 0.65)
			(stroke
				(width 0.05)
				(type solid)
			)
			(fill none)
			(layer "F.CrtYd")
		)
		(fp_rect
			(start -0.8 -0.4)
			(end 0.8 0.4)
			(stroke
				(width 0.15)
				(type solid)
			)
			(fill none)
			(layer "F.Fab")
		)
		(fp_text user "${REFERENCE}"
			(at -1.25 3.898 90)
			(layer "F.Fab")
			(hide yes)
			(effects
				(font
					(size 0.7 0.7)
					(thickness 0.15)
				)
				(justify left bottom)
			)
		)
		(fp_text user "License: Apache-2.0"
			(at -1.25 5.9 90)
			(layer "F.Fab")
			(hide yes)
			(effects
				(font
					(size 0.7 0.7)
					(thickness 0.15)
				)
				(justify left bottom)
			)
		)
		(fp_text user "Author: Antmicro"
			(at -1.25 4.9 90)
			(layer "F.Fab")
			(hide yes)
			(effects
				(font
					(size 0.7 0.7)
					(thickness 0.15)
				)
				(justify left bottom)
			)
		)
		(pad "1" smd roundrect
			(at -0.7 0 90)
			(size 0.8 1)
			(layers "F.Cu" "F.Paste" "F.Mask")
			(roundrect_rratio 0.2)
			(net 641 "/Supply/3V3_OUT")
			(pintype "passive")
		)
		(pad "2" smd roundrect
			(at 0.7 0 90)
			(size 0.8 1)
			(layers "F.Cu" "F.Paste" "F.Mask")
			(roundrect_rratio 0.2)
			(net 87 "+3V3")
			(pintype "passive")
		)
	)
	(footprint "antmicro-footprints:R_0402_1005Metric"
		(layer "F.Cu")
		(at 105.154938 107.045)
		(descr "Resistor SMD 0402")
		(tags "resistor SMD 0402")
		(property "Reference" "R202"
			(at -3.654938 0.405 0)
			(layer "F.SilkS")
			(effects
				(font
					(size 0.7 0.7)
					(thickness 0.15)
				)
				(justify left bottom)
			)
		)
		(property "Value" "R_0R_0402"
			(at 0 1.4 0)
			(layer "F.Fab")
			(effects
				(font
					(size 0.7 0.7)
					(thickness 0.15)
				)
				(justify left bottom)
			)
		)
		(property "Footprint" "antmicro-footprints:R_0402_1005Metric"
			(at 0 0 0)
			(layer "F.Fab")
			(hide yes)
			(effects
				(font
					(size 1.27 1.27)
					(thickness 0.15)
				)
			)
		)
		(property "Datasheet" "https://industrial.panasonic.com/cdbs/www-data/pdf/RDA0000/AOA0000C301.pdf"
			(at 0 0 0)
			(layer "F.Fab")
			(hide yes)
			(effects
				(font
					(size 1.27 1.27)
					(thickness 0.15)
				)
			)
		)
		(property "Author" "Antmicro"
			(at 0 0 0)
			(layer "F.Fab")
			(hide yes)
			(effects
				(font
					(size 1 1)
					(thickness 0.15)
				)
			)
		)
		(property "Current" "1A"
			(at 0 0 0)
			(layer "F.Fab")
			(hide yes)
			(effects
				(font
					(size 1 1)
					(thickness 0.15)
				)
			)
		)
		(property "License" "Apache-2.0"
			(at 0 0 0)
			(layer "F.Fab")
			(hide yes)
			(effects
				(font
					(size 1 1)
					(thickness 0.15)
				)
			)
		)
		(property "MPN" "ERJ2GE0R00X"
			(at 0 0 0)
			(layer "F.Fab")
			(hide yes)
			(effects
				(font
					(size 1 1)
					(thickness 0.15)
				)
			)
		)
		(property "Manufacturer" "Panasonic"
			(at 0 0 0)
			(layer "F.Fab")
			(hide yes)
			(effects
				(font
					(size 1 1)
					(thickness 0.15)
				)
			)
		)
		(property "Tolerance" ""
			(at 0 0 0)
			(layer "F.Fab")
			(hide yes)
			(effects
				(font
					(size 1 1)
					(thickness 0.15)
				)
			)
		)
		(property "Val" "0R"
			(at 0 0 0)
			(layer "F.Fab")
			(hide yes)
			(effects
				(font
					(size 1 1)
					(thickness 0.15)
				)
			)
		)
		(sheetname "USB3")
		(sheetfile "usb3.kicad_sch")
		(attr smd)
		(fp_rect
			(start -0.925 -0.47)
			(end 0.925 0.47)
			(stroke
				(width 0.05)
				(type default)
			)
			(fill none)
			(layer "F.CrtYd")
		)
		(fp_rect
			(start -0.5 -0.25)
			(end 0.5 0.25)
			(stroke
				(width 0.15)
				(type solid)
			)
			(fill none)
			(layer "F.Fab")
		)
		(fp_text user "${REFERENCE}"
			(at -0.95 3.168 0)
			(layer "F.Fab")
			(hide yes)
			(effects
				(font
					(size 0.7 0.7)
					(thickness 0.15)
				)
				(justify left bottom)
			)
		)
		(fp_text user "License: Apache-2.0"
			(at -0.95 5.169 0)
			(layer "F.Fab")
			(hide yes)
			(effects
				(font
					(size 0.7 0.7)
					(thickness 0.15)
				)
				(justify left bottom)
			)
		)
		(fp_text user "Author: Antmicro"
			(at -0.95 4.169 0)
			(layer "F.Fab")
			(hide yes)
			(effects
				(font
					(size 0.7 0.7)
					(thickness 0.15)
				)
				(justify left bottom)
			)
		)
		(pad "1" smd roundrect
			(at -0.48 0)
			(size 0.59 0.64)
			(layers "F.Cu" "F.Paste" "F.Mask")
			(roundrect_rratio 0.25)
			(net 173 "USBSS2_TX_P")
			(pintype "passive")
		)
		(pad "2" smd roundrect
			(at 0.48 0)
			(size 0.59 0.64)
			(layers "F.Cu" "F.Paste" "F.Mask")
			(roundrect_rratio 0.25)
			(net 610 "/USB3/USBSS1_C_TX_N")
			(pintype "passive")
		)
	)
)
